#ISCELL
  mstr_misc prelim *
  *
#ISCELL
  mstr_symbols bom_note *
  *
#ISCELL
  mstr_symbols cad_note *
  *
#ISCELL
  mstr_symbols design_note *
  *
#ISCELL
  mstr_symbols intel_corp_bpage *
  *
#ISCELL
  mstr_standard offpage *
  page21_i10
#ISCELL
  mstr_standard offpage *
  page21_i106
#ISCELL
  mstr_standard offpage *
  page21_i107
#ISCELL
  mstr_standard offpage *
  page21_i108
#ISCELL
  mstr_standard offpage *
  page21_i11
#ISCELL
  mstr_standard offpage *
  page21_i111
#ISCELL
  mstr_standard offpage *
  page21_i12
#ISCELL
  mstr_standard offpage *
  page21_i133
#ISCELL
  mstr_standard offpage *
  page21_i134
#ISCELL
  mstr_standard offpage *
  page21_i135
#ISCELL
  mstr_standard offpage *
  page21_i136
#ISCELL
  mstr_standard offpage *
  page21_i137
#ISCELL
  mstr_standard offpage *
  page21_i145
#ISCELL
  mstr_standard offpage *
  page21_i146
#ISCELL
  mstr_standard offpage *
  page21_i147
#CELL
  mstr_discrete res *
  page21_i149
#ISCELL
  mstr_standard offpage *
  page21_i15
#CELL
  mstr_discrete res *
  page21_i150
#CELL
  mstr_discrete res *
  page21_i151
#CELL
  mstr_discrete res *
  page21_i152
#CELL
  mstr_discrete res *
  page21_i153
#CELL
  mstr_discrete res *
  page21_i154
#ISCELL
  mstr_standard offpage *
  page21_i155
#ISCELL
  mstr_standard offpage *
  page21_i156
#ISCELL
  mstr_standard offpage *
  page21_i157
#ISCELL
  mstr_symbols pvccio_cpu0 *
  page21_i158
#CELL
  mstr_discrete res *
  page21_i159
#CELL
  mstr_discrete res *
  page21_i161
#CELL
  mstr_discrete res *
  page21_i163
#CELL
  mstr_discrete res *
  page21_i164
#ISCELL
  mstr_standard offpage *
  page21_i169
#ISCELL
  mstr_standard offpage *
  page21_i170
#ISCELL
  mstr_standard offpage *
  page21_i172
#ISCELL
  mstr_standard offpage *
  page21_i175
#CELL
  mstr_discrete res *
  page21_i177
#CELL
  mstr_discrete res *
  page21_i178
#CELL
  mstr_discrete res *
  page21_i179
#ISCELL
  mstr_standard offpage *
  page21_i18
#CELL
  mstr_discrete res *
  page21_i180
#CELL
  mstr_discrete res *
  page21_i181
#CELL
  mstr_discrete res *
  page21_i182
#ISCELL
  mstr_symbols gnd *
  page21_i183
#CELL
  mstr_discrete res *
  page21_i184
#CELL
  mstr_discrete res *
  page21_i186
#ISCELL
  mstr_symbols gnd *
  page21_i187
#CELL
  mstr_discrete res *
  page21_i188
#CELL
  mstr_discrete res *
  page21_i189
#ISCELL
  mstr_standard offpage *
  page21_i196
#ISCELL
  mstr_standard offpage *
  page21_i197
#ISCELL
  mstr_standard offpage *
  page21_i2
#ISCELL
  mstr_standard offpage *
  page21_i200
#ISCELL
  mstr_standard offpage *
  page21_i201
#ISCELL
  mstr_standard offpage *
  page21_i202
#CELL
  mstr_discrete res *
  page21_i204
#ISCELL
  mstr_standard offpage *
  page21_i205
#ISCELL
  mstr_standard offpage *
  page21_i209
#ISCELL
  mstr_standard offpage *
  page21_i212
#ISCELL
  mstr_standard offpage *
  page21_i213
#ISCELL
  mstr_standard offpage *
  page21_i214
#ISCELL
  mstr_standard offpage *
  page21_i215
#CELL
  chpset_lib socket_p_mech_a *
  page21_i216
#CELL
  chpset_lib socket_p_mech_a *
  page21_i217
#CELL
  mstr_discrete res *
  page21_i219
#CELL
  mstr_discrete res *
  page21_i227
#ISCELL
  mstr_symbols p3v3_stby *
  page21_i228
#ISCELL
  mstr_standard offpage *
  page21_i233
#ISCELL
  mstr_standard offpage *
  page21_i234
#ISCELL
  mstr_standard offpage *
  page21_i235
#ISCELL
  mstr_standard offpage *
  page21_i236
#ISCELL
  mstr_standard offpage *
  page21_i237
#CELL
  mstr_discrete res *
  page21_i238
#CELL
  mstr_discrete res *
  page21_i239
#CELL
  mstr_discrete res *
  page21_i240
#CELL
  mstr_discrete res *
  page21_i241
#ISCELL
  mstr_symbols p3v3_stby *
  page21_i243
#CELL
  mstr_discrete res *
  page21_i244
#ISCELL
  mstr_standard offpage *
  page21_i247
#ISCELL
  mstr_standard offpage *
  page21_i254
#ISCELL
  mstr_standard offpage *
  page21_i255
#ISCELL
  mstr_standard offpage *
  page21_i256
#ISCELL
  mstr_symbols pvccio_cpu0 *
  page21_i257
#CELL
  mstr_discrete res *
  page21_i258
#CELL
  chpset_lib skx_ext_b *
  page21_i259
#ISCELL
  mstr_standard offpage *
  page21_i260
#ISCELL
  mstr_standard offpage *
  page21_i261
#ISCELL
  mstr_standard offpage *
  page21_i262
#ISCELL
  mstr_standard offpage *
  page21_i263
#ISCELL
  mstr_standard offpage *
  page21_i264
#ISCELL
  mstr_standard offpage *
  page21_i265
#ISCELL
  mstr_standard offpage *
  page21_i266
#ISCELL
  mstr_standard offpage *
  page21_i267
#ISCELL
  mstr_standard offpage *
  page21_i268
#ISCELL
  mstr_standard offpage *
  page21_i4
#ISCELL
  mstr_standard offpage *
  page21_i43
#ISCELL
  mstr_standard offpage *
  page21_i44
#ISCELL
  mstr_standard offpage *
  page21_i47
#ISCELL
  mstr_standard offpage *
  page21_i48
#ISCELL
  mstr_standard offpage *
  page21_i49
#ISCELL
  mstr_standard offpage *
  page21_i5
#ISCELL
  mstr_standard offpage *
  page21_i50
#ISCELL
  mstr_standard offpage *
  page21_i6
#ISCELL
  mstr_standard offpage *
  page21_i66
#ISCELL
  mstr_standard offpage *
  page21_i67
#ISCELL
  mstr_standard offpage *
  page21_i68
#ISCELL
  mstr_standard offpage *
  page21_i69
#ISCELL
  mstr_standard offpage *
  page21_i7
#ISCELL
  mstr_standard offpage *
  page21_i71
#ISCELL
  mstr_standard offpage *
  page21_i72
#ISCELL
  mstr_standard offpage *
  page21_i74
#ISCELL
  mstr_standard offpage *
  page21_i75
#ISCELL
  mstr_standard offpage *
  page21_i76
#ISCELL
  mstr_standard offpage *
  page21_i77
#ISCELL
  mstr_standard offpage *
  page21_i78
#ISCELL
  mstr_standard offpage *
  page21_i79
#ISCELL
  mstr_standard offpage *
  page21_i8
#ISCELL
  mstr_standard offpage *
  page21_i80
#ISCELL
  mstr_standard offpage *
  page21_i9
